(kicad_pcb
	(version 20260206)
	(generator "pcbnew")
	(generator_version "10.0")
	(general
		(thickness 1.6)
		(legacy_teardrops no)
	)
	(paper "A4")
	(title_block
		(title "04192023_DAF0TMB3IC0_F0TG_MB_C_brd_V02_OCP.brd")
		(comment 1 "Grand Teton / footprints 5387-5391 of 8354")
	)
	(layers
		(0 "F.Cu" signal "TOP")
		(4 "In1.Cu" signal "GND")
		(6 "In2.Cu" signal "IN1")
		(8 "In3.Cu" signal "GND1")
		(10 "In4.Cu" signal "IN2")
		(12 "In5.Cu" signal "GND2")
		(14 "In6.Cu" signal "IN3")
		(16 "In7.Cu" signal "GND3")
		(18 "In8.Cu" signal "VCC")
		(20 "In9.Cu" signal "VCC1")
		(22 "In10.Cu" signal "GND4")
		(24 "In11.Cu" signal "IN4")
		(26 "In12.Cu" signal "GND5")
		(28 "In13.Cu" signal "IN5")
		(30 "In14.Cu" signal "GND6")
		(32 "In15.Cu" signal "IN6")
		(34 "In16.Cu" signal "GND7")
		(2 "B.Cu" signal "BOTTOM")
		(9 "F.Adhes" user "F.Adhesive")
		(11 "B.Adhes" user "B.Adhesive")
		(13 "F.Paste" user "Package Geometry/Pastemask Top")
		(15 "B.Paste" user "Package Geometry/Pastemask Bottom")
		(5 "F.SilkS" user "Ref Des/Silkscreen Top")
		(7 "B.SilkS" user "Ref Des/Silkscreen Bottom")
		(1 "F.Mask" user "Board Geometry/Soldermask Top")
		(3 "B.Mask" user "Board Geometry/Soldermask Bottom")
		(17 "Dwgs.User" user "User.Drawings")
		(19 "Cmts.User" user "User.Comments")
		(21 "Eco1.User" user "User.Eco1")
		(23 "Eco2.User" user "User.Eco2")
		(25 "Edge.Cuts" user "Board Geometry/Outline")
		(27 "Margin" user)
		(31 "F.CrtYd" user "Package Geometry/Place Bound Top")
		(29 "B.CrtYd" user "Package Geometry/Place Bound Bottom")
		(35 "F.Fab" user "Ref Des/Assembly Top")
		(33 "B.Fab" user "Ref Des/Assembly Bottom")
	)
	(footprint ""
		(layer "B.Cu")
		(at 191.64046 -190.821564)
		(property "Reference" "R313"
			(at 0 0 0)
			(layer "B.SilkS")
			(hide yes)
			(effects
				(font
					(size 1.27 1.27)
				)
				(justify mirror)
			)
		)
		(property "Value" ""
			(at 0 0 0)
			(layer "B.Fab")
			(effects
				(font
					(size 1.27 1.27)
				)
				(justify mirror)
			)
		)
		(duplicate_pad_numbers_are_jumpers no)
		(fp_line
			(start -0.7874 -0.4064)
			(end -0.7874 0.4064)
			(stroke
				(width 0.1524)
				(type default)
			)
			(layer "B.SilkS")
		)
		(fp_line
			(start -0.7874 0.4064)
			(end 0.7874 0.4064)
			(stroke
				(width 0.1524)
				(type default)
			)
			(layer "B.SilkS")
		)
		(fp_line
			(start 0.7874 -0.4064)
			(end -0.7874 -0.4064)
			(stroke
				(width 0.1524)
				(type default)
			)
			(layer "B.SilkS")
		)
		(fp_line
			(start 0.7874 0.4064)
			(end 0.7874 -0.4064)
			(stroke
				(width 0.1524)
				(type default)
			)
			(layer "B.SilkS")
		)
		(fp_line
			(start -0.67945 -0.3048)
			(end -0.67945 0.3048)
			(stroke
				(width 0.1)
				(type default)
			)
			(layer "B.Fab")
		)
		(fp_line
			(start -0.67945 0.3048)
			(end -0.120396 0.3048)
			(stroke
				(width 0.1)
				(type default)
			)
			(layer "B.Fab")
		)
		(fp_line
			(start -0.12065 -0.3048)
			(end -0.67945 -0.3048)
			(stroke
				(width 0.1)
				(type default)
			)
			(layer "B.Fab")
		)
		(fp_line
			(start -0.12065 -0.2794)
			(end -0.12065 -0.3048)
			(stroke
				(width 0.1)
				(type default)
			)
			(layer "B.Fab")
		)
		(fp_line
			(start -0.120396 0.2794)
			(end 0.12065 0.2794)
			(stroke
				(width 0.1)
				(type default)
			)
			(layer "B.Fab")
		)
		(fp_line
			(start -0.120396 0.3048)
			(end -0.120396 0.2794)
			(stroke
				(width 0.1)
				(type default)
			)
			(layer "B.Fab")
		)
		(fp_line
			(start 0.12065 -0.305054)
			(end 0.12065 -0.2794)
			(stroke
				(width 0.1)
				(type default)
			)
			(layer "B.Fab")
		)
		(fp_line
			(start 0.12065 -0.2794)
			(end -0.12065 -0.2794)
			(stroke
				(width 0.1)
				(type default)
			)
			(layer "B.Fab")
		)
		(fp_line
			(start 0.12065 0.2794)
			(end 0.12065 0.3048)
			(stroke
				(width 0.1)
				(type default)
			)
			(layer "B.Fab")
		)
		(fp_line
			(start 0.12065 0.3048)
			(end 0.67945 0.3048)
			(stroke
				(width 0.1)
				(type default)
			)
			(layer "B.Fab")
		)
		(fp_line
			(start 0.67945 -0.305054)
			(end 0.12065 -0.305054)
			(stroke
				(width 0.1)
				(type default)
			)
			(layer "B.Fab")
		)
		(fp_line
			(start 0.67945 0.3048)
			(end 0.67945 -0.305054)
			(stroke
				(width 0.1)
				(type default)
			)
			(layer "B.Fab")
		)
		(pad "1" smd circle
			(at 0.40005 0 180)
			(size 0 0)
			(layers "B.Cu" "B.Mask" "B.Paste")
			(net "PWRGD_CHK_CPU1_DIMM")
		)
		(pad "2" smd circle
			(at -0.40005 0 180)
			(size 0 0)
			(layers "B.Cu" "B.Mask" "B.Paste")
			(net "PWRGD_CHGL_CPU1")
		)
	)
	(footprint ""
		(layer "B.Cu")
		(at 527.336512 -107.699302 180)
		(property "Reference" "DB12"
			(at 2.546096 -8.857742 270)
			(unlocked yes)
			(layer "B.SilkS")
			(effects
				(font
					(size 0.7874 0.5842)
					(thickness 0.1524)
				)
				(justify left mirror)
			)
		)
		(property "Value" ""
			(at 0 0 0)
			(layer "B.Fab")
			(effects
				(font
					(size 1.27 1.27)
				)
				(justify mirror)
			)
		)
		(duplicate_pad_numbers_are_jumpers no)
		(fp_line
			(start 3.330702 -4.771136)
			(end -3.330702 -4.771136)
			(stroke
				(width 0.1524)
				(type default)
			)
			(layer "B.SilkS")
		)
		(fp_line
			(start 0 4.011168)
			(end 3.330702 -4.771136)
			(stroke
				(width 0.1524)
				(type default)
			)
			(layer "B.SilkS")
		)
		(fp_line
			(start -3.330702 -4.771136)
			(end 0 4.011168)
			(stroke
				(width 0.1524)
				(type default)
			)
			(layer "B.SilkS")
		)
		(fp_line
			(start 3.330702 -4.771136)
			(end -3.330702 -4.771136)
			(stroke
				(width 0.1)
				(type default)
			)
			(layer "B.Fab")
		)
		(fp_line
			(start 0 4.011168)
			(end 3.330702 -4.771136)
			(stroke
				(width 0.1)
				(type default)
			)
			(layer "B.Fab")
		)
		(fp_line
			(start -3.330702 -4.771136)
			(end 0 4.011168)
			(stroke
				(width 0.1)
				(type default)
			)
			(layer "B.Fab")
		)
		(pad "1" thru_hole circle
			(at 0 0)
			(size 2.159 2.159)
			(drill 1.7018)
			(layers "*.Cu" "*.Mask")
			(remove_unused_layers no)
			(net "T1_GND")
			(clearance 0.0254)
			(thermal_gap 0.0254)
		)
		(pad "2" thru_hole circle
			(at 1.27 -3.348736)
			(size 2.159 2.159)
			(drill 1.7018)
			(layers "*.Cu" "*.Mask")
			(remove_unused_layers no)
			(net "TDR_SE_50_OHM_BOT")
			(clearance 0.0254)
			(thermal_gap 0.0254)
		)
		(pad "3" thru_hole circle
			(at -1.27 -3.348736)
			(size 2.159 2.159)
			(drill 1.7018)
			(layers "*.Cu" "*.Mask")
			(remove_unused_layers no)
			(net "TDR_SE_50_OHM_BOT")
			(clearance 0.0254)
			(thermal_gap 0.0254)
		)
	)
	(footprint ""
		(layer "B.Cu")
		(at 346.913454 -267.52931)
		(property "Reference" "C2512"
			(at 0 0 0)
			(layer "B.SilkS")
			(hide yes)
			(effects
				(font
					(size 1.27 1.27)
				)
				(justify mirror)
			)
		)
		(property "Value" ""
			(at 0 0 0)
			(layer "B.Fab")
			(effects
				(font
					(size 1.27 1.27)
				)
				(justify mirror)
			)
		)
		(duplicate_pad_numbers_are_jumpers no)
		(fp_line
			(start -0.7874 -0.4064)
			(end -0.7874 0.4064)
			(stroke
				(width 0.1524)
				(type default)
			)
			(layer "B.SilkS")
		)
		(fp_line
			(start -0.7874 0.4064)
			(end 0.7874 0.4064)
			(stroke
				(width 0.1524)
				(type default)
			)
			(layer "B.SilkS")
		)
		(fp_line
			(start 0.7874 -0.4064)
			(end -0.7874 -0.4064)
			(stroke
				(width 0.1524)
				(type default)
			)
			(layer "B.SilkS")
		)
		(fp_line
			(start 0.7874 0.4064)
			(end 0.7874 -0.4064)
			(stroke
				(width 0.1524)
				(type default)
			)
			(layer "B.SilkS")
		)
		(fp_line
			(start -0.67945 -0.3048)
			(end -0.67945 0.3048)
			(stroke
				(width 0.1)
				(type default)
			)
			(layer "B.Fab")
		)
		(fp_line
			(start -0.67945 0.3048)
			(end -0.120396 0.3048)
			(stroke
				(width 0.1)
				(type default)
			)
			(layer "B.Fab")
		)
		(fp_line
			(start -0.12065 -0.3048)
			(end -0.67945 -0.3048)
			(stroke
				(width 0.1)
				(type default)
			)
			(layer "B.Fab")
		)
		(fp_line
			(start -0.12065 -0.2794)
			(end -0.12065 -0.3048)
			(stroke
				(width 0.1)
				(type default)
			)
			(layer "B.Fab")
		)
		(fp_line
			(start -0.120396 0.2794)
			(end 0.12065 0.2794)
			(stroke
				(width 0.1)
				(type default)
			)
			(layer "B.Fab")
		)
		(fp_line
			(start -0.120396 0.3048)
			(end -0.120396 0.2794)
			(stroke
				(width 0.1)
				(type default)
			)
			(layer "B.Fab")
		)
		(fp_line
			(start 0.12065 -0.305054)
			(end 0.12065 -0.2794)
			(stroke
				(width 0.1)
				(type default)
			)
			(layer "B.Fab")
		)
		(fp_line
			(start 0.12065 -0.2794)
			(end -0.12065 -0.2794)
			(stroke
				(width 0.1)
				(type default)
			)
			(layer "B.Fab")
		)
		(fp_line
			(start 0.12065 0.2794)
			(end 0.12065 0.3048)
			(stroke
				(width 0.1)
				(type default)
			)
			(layer "B.Fab")
		)
		(fp_line
			(start 0.12065 0.3048)
			(end 0.67945 0.3048)
			(stroke
				(width 0.1)
				(type default)
			)
			(layer "B.Fab")
		)
		(fp_line
			(start 0.67945 -0.305054)
			(end 0.12065 -0.305054)
			(stroke
				(width 0.1)
				(type default)
			)
			(layer "B.Fab")
		)
		(fp_line
			(start 0.67945 0.3048)
			(end 0.67945 -0.305054)
			(stroke
				(width 0.1)
				(type default)
			)
			(layer "B.Fab")
		)
		(pad "1" smd circle
			(at 0.40005 0 180)
			(size 0 0)
			(layers "B.Cu" "B.Mask" "B.Paste")
			(net "PVDD_33_S5")
		)
		(pad "2" smd circle
			(at -0.40005 0 180)
			(size 0 0)
			(layers "B.Cu" "B.Mask" "B.Paste")
			(net "GND")
		)
	)
	(footprint ""
		(layer "B.Cu")
		(at 212.471508 2.542794 180)
		(property "Reference" "J121"
			(at 4.540504 -1.317498 270)
			(unlocked yes)
			(layer "B.SilkS")
			(effects
				(font
					(size 0.7874 0.5842)
					(thickness 0.1524)
				)
				(justify left mirror)
			)
		)
		(property "Value" ""
			(at 0 0 0)
			(layer "B.Fab")
			(effects
				(font
					(size 1.27 1.27)
				)
				(justify mirror)
			)
		)
		(duplicate_pad_numbers_are_jumpers no)
		(fp_line
			(start 1.2192 2.06756)
			(end 1.2192 -2.06756)
			(stroke
				(width 0.1524)
				(type default)
			)
			(layer "B.SilkS")
		)
		(fp_line
			(start 1.2192 -2.06756)
			(end -1.2192 -2.06756)
			(stroke
				(width 0.1524)
				(type default)
			)
			(layer "B.SilkS")
		)
		(fp_line
			(start -1.2192 2.06756)
			(end 1.2192 2.06756)
			(stroke
				(width 0.1524)
				(type default)
			)
			(layer "B.SilkS")
		)
		(fp_line
			(start -1.2192 -2.06756)
			(end -1.2192 2.06756)
			(stroke
				(width 0.1524)
				(type default)
			)
			(layer "B.SilkS")
		)
		(pad "" np_thru_hole circle
			(at -3.4671 -1.27 90)
			(size 1.0414 1.0414)
			(drill 1.0414)
			(layers "*.Cu" "*.Mask")
			(clearance 0.381)
			(thermal_gap 0.381)
		)
		(pad "" np_thru_hole circle
			(at -3.4671 1.27 90)
			(size 1.0414 1.0414)
			(drill 1.0414)
			(layers "*.Cu" "*.Mask")
			(clearance 0.381)
			(thermal_gap 0.381)
		)
		(pad "" np_thru_hole circle
			(at 2.8829 -1.27 90)
			(size 1.0414 1.0414)
			(drill 1.0414)
			(layers "*.Cu" "*.Mask")
			(clearance 0.381)
			(thermal_gap 0.381)
		)
		(pad "" np_thru_hole circle
			(at 2.8829 1.27 90)
			(size 1.0414 1.0414)
			(drill 1.0414)
			(layers "*.Cu" "*.Mask")
			(clearance 0.381)
			(thermal_gap 0.381)
		)
		(pad "1" smd rect
			(at -0.8255 -0.249936 90)
			(size 0.3048 0.508)
			(layers "B.Cu" "B.Mask" "B.Paste")
			(net "DELTA_L_85_10INCH_IN6_DN")
		)
		(pad "2" smd rect
			(at -0.8255 0.249936 90)
			(size 0.3048 0.508)
			(layers "B.Cu" "B.Mask" "B.Paste")
			(net "DELTA_L_85_10INCH_IN6_DP")
		)
		(pad "3" smd circle
			(at 0 0)
			(size 0 0)
			(layers "B.Cu" "B.Mask" "B.Paste")
			(net "DELTA_L_GND_1")
		)
		(zone
			(layers "F.Cu" "B.Cu" "In1.Cu" "In2.Cu" "In3.Cu" "In4.Cu" "In5.Cu" "In6.Cu"
				"In7.Cu" "In8.Cu" "In9.Cu" "In10.Cu" "In11.Cu" "In12.Cu" "In13.Cu" "In14.Cu"
				"In15.Cu" "In16.Cu"
			)
			(hatch none 0.5)
			(connect_pads
				(clearance 0)
			)
			(min_thickness 0.25)
			(keepout
				(tracks not_allowed)
				(vias allowed)
				(pads allowed)
				(copperpour not_allowed)
				(footprints allowed)
			)
			(placement
				(enabled no)
				(sheetname "")
			)
			(fill
				(thermal_gap 0.5)
				(thermal_bridge_width 0.5)
				(island_removal_mode 0)
			)
			(polygon
				(pts
					(arc
						(start 210.515708 1.272794)
						(mid 208.661508 1.272794)
						(end 210.515708 1.272794)
					)
				)
			)
		)
		(zone
			(layers "F.Cu" "B.Cu" "In1.Cu" "In2.Cu" "In3.Cu" "In4.Cu" "In5.Cu" "In6.Cu"
				"In7.Cu" "In8.Cu" "In9.Cu" "In10.Cu" "In11.Cu" "In12.Cu" "In13.Cu" "In14.Cu"
				"In15.Cu" "In16.Cu"
			)
			(hatch none 0.5)
			(connect_pads
				(clearance 0)
			)
			(min_thickness 0.25)
			(keepout
				(tracks not_allowed)
				(vias allowed)
				(pads allowed)
				(copperpour not_allowed)
				(footprints allowed)
			)
			(placement
				(enabled no)
				(sheetname "")
			)
			(fill
				(thermal_gap 0.5)
				(thermal_bridge_width 0.5)
				(island_removal_mode 0)
			)
			(polygon
				(pts
					(arc
						(start 210.515708 3.812794)
						(mid 208.661508 3.812794)
						(end 210.515708 3.812794)
					)
				)
			)
		)
		(zone
			(layers "F.Cu" "B.Cu" "In1.Cu" "In2.Cu" "In3.Cu" "In4.Cu" "In5.Cu" "In6.Cu"
				"In7.Cu" "In8.Cu" "In9.Cu" "In10.Cu" "In11.Cu" "In12.Cu" "In13.Cu" "In14.Cu"
				"In15.Cu" "In16.Cu"
			)
			(hatch none 0.5)
			(connect_pads
				(clearance 0)
			)
			(min_thickness 0.25)
			(keepout
				(tracks not_allowed)
				(vias allowed)
				(pads allowed)
				(copperpour not_allowed)
				(footprints allowed)
			)
			(placement
				(enabled no)
				(sheetname "")
			)
			(fill
				(thermal_gap 0.5)
				(thermal_bridge_width 0.5)
				(island_removal_mode 0)
			)
			(polygon
				(pts
					(arc
						(start 216.865708 1.272794)
						(mid 215.011508 1.272794)
						(end 216.865708 1.272794)
					)
				)
			)
		)
		(zone
			(layers "F.Cu" "B.Cu" "In1.Cu" "In2.Cu" "In3.Cu" "In4.Cu" "In5.Cu" "In6.Cu"
				"In7.Cu" "In8.Cu" "In9.Cu" "In10.Cu" "In11.Cu" "In12.Cu" "In13.Cu" "In14.Cu"
				"In15.Cu" "In16.Cu"
			)
			(hatch none 0.5)
			(connect_pads
				(clearance 0)
			)
			(min_thickness 0.25)
			(keepout
				(tracks not_allowed)
				(vias allowed)
				(pads allowed)
				(copperpour not_allowed)
				(footprints allowed)
			)
			(placement
				(enabled no)
				(sheetname "")
			)
			(fill
				(thermal_gap 0.5)
				(thermal_bridge_width 0.5)
				(island_removal_mode 0)
			)
			(polygon
				(pts
					(arc
						(start 216.865708 3.812794)
						(mid 215.011508 3.812794)
						(end 216.865708 3.812794)
					)
				)
			)
		)
		(zone
			(layer "B.Cu")
			(hatch none 0.5)
			(connect_pads
				(clearance 0)
			)
			(min_thickness 0.25)
			(keepout
				(tracks not_allowed)
				(vias allowed)
				(pads allowed)
				(copperpour not_allowed)
				(footprints allowed)
			)
			(placement
				(enabled no)
				(sheetname "")
			)
			(fill
				(thermal_gap 0.5)
				(thermal_bridge_width 0.5)
				(island_removal_mode 0)
			)
			(polygon
				(pts
					(xy 213.589108 3.091434) (xy 213.589108 2.99593) (xy 212.992208 2.99593) (xy 212.992208 2.58953)
					(xy 213.589108 2.58953) (xy 213.589108 2.496058) (xy 212.992208 2.496058) (xy 212.992208 2.089658)
					(xy 213.589108 2.089658) (xy 213.589108 1.994154) (xy 212.890608 1.994154) (xy 212.890608 3.091434)
				)
			)
		)
	)
	(footprint ""
		(layer "B.Cu")
		(at 48.591216 -390.560052 90)
		(property "Reference" "C259"
			(at 0 0 90)
			(layer "B.SilkS")
			(hide yes)
			(effects
				(font
					(size 1.27 1.27)
				)
				(justify mirror)
			)
		)
		(property "Value" ""
			(at 0 0 90)
			(layer "B.Fab")
			(effects
				(font
					(size 1.27 1.27)
				)
				(justify mirror)
			)
		)
		(duplicate_pad_numbers_are_jumpers no)
		(fp_line
			(start 0.7874 -0.4064)
			(end -0.7874 -0.4064)
			(stroke
				(width 0.1524)
				(type default)
			)
			(layer "B.SilkS")
		)
		(fp_line
			(start -0.7874 -0.4064)
			(end -0.7874 0.4064)
			(stroke
				(width 0.1524)
				(type default)
			)
			(layer "B.SilkS")
		)
		(fp_line
			(start 0.7874 0.4064)
			(end 0.7874 -0.4064)
			(stroke
				(width 0.1524)
				(type default)
			)
			(layer "B.SilkS")
		)
		(fp_line
			(start -0.7874 0.4064)
			(end 0.7874 0.4064)
			(stroke
				(width 0.1524)
				(type default)
			)
			(layer "B.SilkS")
		)
		(fp_line
			(start 0.67945 -0.305054)
			(end 0.12065 -0.305054)
			(stroke
				(width 0.1)
				(type default)
			)
			(layer "B.Fab")
		)
		(fp_line
			(start 0.12065 -0.305054)
			(end 0.12065 -0.2794)
			(stroke
				(width 0.1)
				(type default)
			)
			(layer "B.Fab")
		)
		(fp_line
			(start -0.12065 -0.3048)
			(end -0.67945 -0.3048)
			(stroke
				(width 0.1)
				(type default)
			)
			(layer "B.Fab")
		)
		(fp_line
			(start -0.67945 -0.3048)
			(end -0.67945 0.3048)
			(stroke
				(width 0.1)
				(type default)
			)
			(layer "B.Fab")
		)
		(fp_line
			(start 0.12065 -0.2794)
			(end -0.12065 -0.2794)
			(stroke
				(width 0.1)
				(type default)
			)
			(layer "B.Fab")
		)
		(fp_line
			(start -0.12065 -0.2794)
			(end -0.12065 -0.3048)
			(stroke
				(width 0.1)
				(type default)
			)
			(layer "B.Fab")
		)
		(fp_line
			(start 0.12065 0.2794)
			(end 0.12065 0.3048)
			(stroke
				(width 0.1)
				(type default)
			)
			(layer "B.Fab")
		)
		(fp_line
			(start -0.120396 0.2794)
			(end 0.12065 0.2794)
			(stroke
				(width 0.1)
				(type default)
			)
			(layer "B.Fab")
		)
		(fp_line
			(start 0.67945 0.3048)
			(end 0.67945 -0.305054)
			(stroke
				(width 0.1)
				(type default)
			)
			(layer "B.Fab")
		)
		(fp_line
			(start 0.12065 0.3048)
			(end 0.67945 0.3048)
			(stroke
				(width 0.1)
				(type default)
			)
			(layer "B.Fab")
		)
		(fp_line
			(start -0.120396 0.3048)
			(end -0.120396 0.2794)
			(stroke
				(width 0.1)
				(type default)
			)
			(layer "B.Fab")
		)
		(fp_line
			(start -0.67945 0.3048)
			(end -0.120396 0.3048)
			(stroke
				(width 0.1)
				(type default)
			)
			(layer "B.Fab")
		)
		(pad "1" smd circle
			(at 0.40005 0 270)
			(size 0 0)
			(layers "B.Cu" "B.Mask" "B.Paste")
			(net "P0V9_CPU1_RT0_2A")
		)
		(pad "2" smd circle
			(at -0.40005 0 270)
			(size 0 0)
			(layers "B.Cu" "B.Mask" "B.Paste")
			(net "GND")
		)
	)
)
